# BASEBOARD_FAB2 (Tioga Pass) — schematic netlist excerpt (pin names and nets, part order shuffled) for the footprints in the layout excerpt that follows; sources: Cadence DE-HDL packaged netlist, KiCad conversion of Wiwynn_Tioga_Pass_MB.brd

C3P37  CAP  0.22UF 16V 10% X7R  pkg 0402  page 107 : A = P3E_CPU0_PE1_SS_TXN<6> ; B = P3E_CPU0_PE1_PCH_TXN<6>
R3N1  RES  169 1.0% CHIP  pkg 0402  page 114 : A = A_PCH_XCLK_BIASREF ; B = GND
R2U42  RES  221 1.0% CHIP  pkg 0402  page 161 : A = FAN_PWM_OUT_SYS0_BUF ; B = FAN_PWM_OUT_SYS0_R

(kicad_pcb
	(version 20260206)
	(generator "pcbnew")
	(generator_version "10.0")
	(general
		(thickness 1.6)
		(legacy_teardrops no)
	)
	(paper "A4")
	(title_block
		(title "Wiwynn_Tioga_Pass_MB.brd")
		(comment 1 "Tioga Pass / footprints 4535-4537 of 4770")
	)
	(layers
		(0 "F.Cu" signal "TOP")
		(4 "In1.Cu" signal "L2GND")
		(6 "In2.Cu" signal "L3")
		(8 "In3.Cu" signal "L4GND")
		(10 "In4.Cu" signal "L5")
		(12 "In5.Cu" signal "L6GND")
		(14 "In6.Cu" signal "L7VCC")
		(16 "In7.Cu" signal "L8VCC")
		(18 "In8.Cu" signal "L9GND")
		(20 "In9.Cu" signal "L10")
		(22 "In10.Cu" signal "L11GND")
		(24 "In11.Cu" signal "L12")
		(26 "In12.Cu" signal "L13GND")
		(2 "B.Cu" signal "BOTTOM")
		(9 "F.Adhes" user "F.Adhesive")
		(11 "B.Adhes" user "B.Adhesive")
		(13 "F.Paste" user "Package Geometry/Pastemask Top")
		(15 "B.Paste" user "Package Geometry/Pastemask Bottom")
		(5 "F.SilkS" user "Ref Des/Silkscreen Top")
		(7 "B.SilkS" user "Ref Des/Silkscreen Bottom")
		(1 "F.Mask" user "Board Geometry/Soldermask Top")
		(3 "B.Mask" user "Board Geometry/Soldermask Bottom")
		(17 "Dwgs.User" user "User.Drawings")
		(19 "Cmts.User" user "User.Comments")
		(21 "Eco1.User" user "User.Eco1")
		(23 "Eco2.User" user "User.Eco2")
		(25 "Edge.Cuts" user "Board Geometry/Outline")
		(27 "Margin" user)
		(31 "F.CrtYd" user "Package Geometry/Place Bound Top")
		(29 "B.CrtYd" user "Package Geometry/Place Bound Bottom")
		(35 "F.Fab" user "Ref Des/Assembly Top")
		(33 "B.Fab" user "Ref Des/Assembly Bottom")
	)
	(footprint ""
		(layer "B.Cu")
		(at 377.589288 -110.817914)
		(property "Reference" "R3N1"
			(at 0 0 0)
			(layer "B.SilkS")
			(hide yes)
			(effects
				(font
					(size 1.27 1.27)
				)
				(justify mirror)
			)
		)
		(property "Value" ""
			(at 0 0 0)
			(layer "B.Fab")
			(effects
				(font
					(size 1.27 1.27)
				)
				(justify mirror)
			)
		)
		(duplicate_pad_numbers_are_jumpers no)
		(fp_poly
			(pts
				(xy 0.2794 -0.1016) (xy -0.2794 -0.1016) (xy -0.2794 0.9906) (xy 0.2794 0.9906)
			)
			(stroke
				(width 0)
				(type default)
			)
			(fill no)
			(layer "B.CrtYd")
		)
		(fp_line
			(start -0.2794 -0.1016)
			(end 0.2794 -0.1016)
			(stroke
				(width 0.1)
				(type default)
			)
			(layer "B.Fab")
		)
		(fp_line
			(start -0.2794 0.9906)
			(end -0.2794 -0.1016)
			(stroke
				(width 0.1)
				(type default)
			)
			(layer "B.Fab")
		)
		(fp_line
			(start 0.2794 -0.1016)
			(end 0.2794 0.9906)
			(stroke
				(width 0.1)
				(type default)
			)
			(layer "B.Fab")
		)
		(fp_line
			(start 0.2794 0.9906)
			(end -0.2794 0.9906)
			(stroke
				(width 0.1)
				(type default)
			)
			(layer "B.Fab")
		)
		(pad "1" smd rect
			(at 0 0 180)
			(size 0.508 0.508)
			(layers "B.Cu" "B.Mask" "B.Paste")
			(net "A_PCH_XCLK_BIASREF")
		)
		(pad "2" smd rect
			(at 0 0.889 180)
			(size 0.508 0.508)
			(layers "B.Cu" "B.Mask" "B.Paste")
			(net "GND")
		)
		(zone
			(layer "B.Cu")
			(hatch none 0.5)
			(connect_pads
				(clearance 0)
			)
			(min_thickness 0.25)
			(keepout
				(tracks allowed)
				(vias not_allowed)
				(pads allowed)
				(copperpour not_allowed)
				(footprints allowed)
			)
			(placement
				(enabled no)
				(sheetname "")
			)
			(fill
				(thermal_gap 0.5)
				(thermal_bridge_width 0.5)
				(island_removal_mode 0)
			)
			(polygon
				(pts
					(xy 377.843288 -110.563914) (xy 377.335288 -110.563914) (xy 377.335288 -110.182914) (xy 377.843288 -110.182914)
				)
			)
		)
		(zone
			(layer "B.Cu")
			(hatch none 0.5)
			(connect_pads
				(clearance 0)
			)
			(min_thickness 0.25)
			(keepout
				(tracks not_allowed)
				(vias allowed)
				(pads allowed)
				(copperpour not_allowed)
				(footprints allowed)
			)
			(placement
				(enabled no)
				(sheetname "")
			)
			(fill
				(thermal_gap 0.5)
				(thermal_bridge_width 0.5)
				(island_removal_mode 0)
			)
			(polygon
				(pts
					(xy 377.843288 -110.182914) (xy 377.335288 -110.182914) (xy 377.335288 -110.563914) (xy 377.843288 -110.563914)
				)
			)
		)
	)
	(footprint ""
		(layer "B.Cu")
		(at 409.702 2.722372)
		(property "Reference" "R2U42"
			(at 0 0 0)
			(layer "B.SilkS")
			(hide yes)
			(effects
				(font
					(size 1.27 1.27)
				)
				(justify mirror)
			)
		)
		(property "Value" ""
			(at 0 0 0)
			(layer "B.Fab")
			(effects
				(font
					(size 1.27 1.27)
				)
				(justify mirror)
			)
		)
		(duplicate_pad_numbers_are_jumpers no)
		(fp_poly
			(pts
				(xy 0.2794 -0.1016) (xy -0.2794 -0.1016) (xy -0.2794 0.9906) (xy 0.2794 0.9906)
			)
			(stroke
				(width 0)
				(type default)
			)
			(fill no)
			(layer "B.CrtYd")
		)
		(fp_line
			(start -0.2794 -0.1016)
			(end 0.2794 -0.1016)
			(stroke
				(width 0.1)
				(type default)
			)
			(layer "B.Fab")
		)
		(fp_line
			(start -0.2794 0.9906)
			(end -0.2794 -0.1016)
			(stroke
				(width 0.1)
				(type default)
			)
			(layer "B.Fab")
		)
		(fp_line
			(start 0.2794 -0.1016)
			(end 0.2794 0.9906)
			(stroke
				(width 0.1)
				(type default)
			)
			(layer "B.Fab")
		)
		(fp_line
			(start 0.2794 0.9906)
			(end -0.2794 0.9906)
			(stroke
				(width 0.1)
				(type default)
			)
			(layer "B.Fab")
		)
		(pad "1" smd rect
			(at 0 0 180)
			(size 0.508 0.508)
			(layers "B.Cu" "B.Mask" "B.Paste")
			(net "FAN_PWM_OUT_SYS0_BUF")
		)
		(pad "2" smd rect
			(at 0 0.889 180)
			(size 0.508 0.508)
			(layers "B.Cu" "B.Mask" "B.Paste")
			(net "FAN_PWM_OUT_SYS0_R")
		)
		(zone
			(layer "B.Cu")
			(hatch none 0.5)
			(connect_pads
				(clearance 0)
			)
			(min_thickness 0.25)
			(keepout
				(tracks allowed)
				(vias not_allowed)
				(pads allowed)
				(copperpour not_allowed)
				(footprints allowed)
			)
			(placement
				(enabled no)
				(sheetname "")
			)
			(fill
				(thermal_gap 0.5)
				(thermal_bridge_width 0.5)
				(island_removal_mode 0)
			)
			(polygon
				(pts
					(xy 409.956 2.976372) (xy 409.448 2.976372) (xy 409.448 3.357372) (xy 409.956 3.357372)
				)
			)
		)
		(zone
			(layer "B.Cu")
			(hatch none 0.5)
			(connect_pads
				(clearance 0)
			)
			(min_thickness 0.25)
			(keepout
				(tracks not_allowed)
				(vias allowed)
				(pads allowed)
				(copperpour not_allowed)
				(footprints allowed)
			)
			(placement
				(enabled no)
				(sheetname "")
			)
			(fill
				(thermal_gap 0.5)
				(thermal_bridge_width 0.5)
				(island_removal_mode 0)
			)
			(polygon
				(pts
					(xy 409.956 3.357372) (xy 409.448 3.357372) (xy 409.448 2.976372) (xy 409.956 2.976372)
				)
			)
		)
	)
	(footprint ""
		(layer "B.Cu")
		(at 357.133398 -77.915516 180)
		(property "Reference" "C3P37"
			(at 0 0 0)
			(layer "B.SilkS")
			(hide yes)
			(effects
				(font
					(size 1.27 1.27)
				)
				(justify mirror)
			)
		)
		(property "Value" ""
			(at 0 0 0)
			(layer "B.Fab")
			(effects
				(font
					(size 1.27 1.27)
				)
				(justify mirror)
			)
		)
		(duplicate_pad_numbers_are_jumpers no)
		(fp_poly
			(pts
				(xy -0.3048 -0.1016) (xy -0.3048 0.9906) (xy 0.3048 0.9906) (xy 0.3048 -0.1016)
			)
			(stroke
				(width 0)
				(type default)
			)
			(fill no)
			(layer "B.CrtYd")
		)
		(fp_line
			(start 0.3048 0.9906)
			(end -0.3048 0.9906)
			(stroke
				(width 0.1)
				(type default)
			)
			(layer "B.Fab")
		)
		(fp_line
			(start 0.3048 -0.1016)
			(end 0.3048 0.9906)
			(stroke
				(width 0.1)
				(type default)
			)
			(layer "B.Fab")
		)
		(fp_line
			(start -0.3048 0.9906)
			(end -0.3048 -0.1016)
			(stroke
				(width 0.1)
				(type default)
			)
			(layer "B.Fab")
		)
		(fp_line
			(start -0.3048 -0.1016)
			(end 0.3048 -0.1016)
			(stroke
				(width 0.1)
				(type default)
			)
			(layer "B.Fab")
		)
		(pad "1" smd rect
			(at 0 0)
			(size 0.508 0.508)
			(layers "B.Cu" "B.Mask" "B.Paste")
			(net "P3E_CPU0_PE1_SS_TXN<6>")
		)
		(pad "2" smd rect
			(at 0 0.889)
			(size 0.508 0.508)
			(layers "B.Cu" "B.Mask" "B.Paste")
			(net "P3E_CPU0_PE1_PCH_TXN<6>")
		)
		(zone
			(layer "B.Cu")
			(hatch none 0.5)
			(connect_pads
				(clearance 0)
			)
			(min_thickness 0.25)
			(keepout
				(tracks not_allowed)
				(vias allowed)
				(pads allowed)
				(copperpour not_allowed)
				(footprints allowed)
			)
			(placement
				(enabled no)
				(sheetname "")
			)
			(fill
				(thermal_gap 0.5)
				(thermal_bridge_width 0.5)
				(island_removal_mode 0)
			)
			(polygon
				(pts
					(xy 356.879398 -78.550516) (xy 357.387398 -78.550516) (xy 357.387398 -78.169516) (xy 356.879398 -78.169516)
				)
			)
		)
		(zone
			(layer "B.Cu")
			(hatch none 0.5)
			(connect_pads
				(clearance 0)
			)
			(min_thickness 0.25)
			(keepout
				(tracks allowed)
				(vias not_allowed)
				(pads allowed)
				(copperpour not_allowed)
				(footprints allowed)
			)
			(placement
				(enabled no)
				(sheetname "")
			)
			(fill
				(thermal_gap 0.5)
				(thermal_bridge_width 0.5)
				(island_removal_mode 0)
			)
			(polygon
				(pts
					(xy 356.879398 -78.169516) (xy 357.387398 -78.169516) (xy 357.387398 -78.550516) (xy 356.879398 -78.550516)
				)
			)
		)
	)
)
